# T6G (Grand Teton) — schematic netlist excerpt (pin names and nets, part order shuffled) for the footprints in the layout excerpt that follows; sources: Cadence DE-HDL packaged netlist, KiCad conversion of 04192023_DAF0TMB3IC0_F0TG_MB_C_brd_V02_OCP.brd

J19  SCONN288_DDR506112002KQ  IO  pkg DDR288S_1-1VXC  page 89
  VIN_BULK0  = P12V_MEM_CPU0
  RFU0  = NC
  VIN_MGMT  = P3V3_AUX
  HSCL  = I3C_SPD_DDRD_CPU0_SCL
  HSDA  = I3C_SPD_DDRD_CPU0_SDA
  VSS0  = GND
  DQ0_A  = M_D_CPU0_SA_DQ<0>
  VSS1  = GND
  DQ1_A  = M_D_CPU0_SA_DQ<1>
  VSS2  = GND
  DQS0_A_T  = M_D_CPU0_SA_DQS_DP<0>
  DQS0_A_C  = M_D_CPU0_SA_DQS_DN<0>
  VSS3  = GND
  DQ4_A  = M_D_CPU0_SA_DQ<4>
  VSS4  = GND
  DQ5_A  = M_D_CPU0_SA_DQ<5>
  VSS5  = GND
  DQ8_A  = M_D_CPU0_SA_DQ<8>
  VSS6  = GND
  DQ9_A  = M_D_CPU0_SA_DQ<9>
  VSS7  = GND
  DQS1_A_T  = M_D_CPU0_SA_DQS_DP<1>
  DQS1_A_C  = M_D_CPU0_SA_DQS_DN<1>
  VSS8  = GND
  DQ12_A  = M_D_CPU0_SA_DQ<12>
  VSS9  = GND
  DQ13_A  = M_D_CPU0_SA_DQ<13>
  VSS10  = GND
  DQ16_A  = M_D_CPU0_SA_DQ<16>
  VSS11  = GND
  DQ17_A  = M_D_CPU0_SA_DQ<17>
  VSS12  = GND
  DQS2_A_T  = M_D_CPU0_SA_DQS_DP<2>
  DQS2_A_C  = M_D_CPU0_SA_DQS_DN<2>
  VSS13  = GND
  DQ20_A  = M_D_CPU0_SA_DQ<20>
  VSS14  = GND
  DQ21_A  = M_D_CPU0_SA_DQ<21>
  VSS15  = GND
  DQ24_A  = M_D_CPU0_SA_DQ<24>
  VSS16  = GND
  DQ25_A  = M_D_CPU0_SA_DQ<25>
  VSS17  = GND
  DQS3_A_T  = M_D_CPU0_SA_DQS_DP<3>
  DQS3_A_C  = M_D_CPU0_SA_DQS_DN<3>
  VSS18  = GND
  DQ28_A  = M_D_CPU0_SA_DQ<28>
  VSS19  = GND
  DQ29_A  = M_D_CPU0_SA_DQ<29>
  VSS20  = GND
  CB0_A  = M_D_CPU0_SA_CB<0>
  VSS21  = GND
  CB1_A  = M_D_CPU0_SA_CB<1>
  VSS22  = GND
  DQS4_A_T  = M_D_CPU0_SA_DQS_DP<4>
  DQS4_A_C  = M_D_CPU0_SA_DQS_DN<4>
  VSS23  = GND
  CB4_A  = M_D_CPU0_SA_CB<4>
  VSS24  = GND
  CB5_A  = M_D_CPU0_SA_CB<5>
  VSS25  = GND
  ALERT_N  = M_D_CPU0_ALERT_N
  VSS26  = GND
  CS0_A_N  = M_D_CPU0_SA_CS_N<0>
  VSS27  = GND
  CA0_A  = M_D_CPU0_SA_CA<0>
  VSS28  = GND
  CA2_A  = M_D_CPU0_SA_CA<2>
  VSS29  = GND
  CA4_A  = M_D_CPU0_SA_CA<4>
  VSS30  = GND
  CA6_A  = M_D_CPU0_SA_CA<6>
  VSS31  = GND
  PAR_A  = M_D_CPU0_SA_PAR
  VSS32  = GND
  CA0_B  = M_D_CPU0_SB_CA<0>
  VSS33  = GND
  CA2_B  = M_D_CPU0_SB_CA<2>
  VSS34  = GND
  CA4_B  = M_D_CPU0_SB_CA<4>
  VSS35  = GND
  CA6_B  = M_D_CPU0_SB_CA<6>
  VSS36  = GND
  CS0_B_N  = M_D_CPU0_SB_CS_N<0>
  VSS37  = GND
  \lbd||rsp_a_n\  = M_D_CPU0_SA_RSP<0>
  \lbs||rsp_b_n\  = M_D_CPU0_SB_RSP<0>
  VSS38  = GND
  CB4_B  = M_D_CPU0_SB_CB<4>
  VSS39  = GND
  CB5_B  = M_D_CPU0_SB_CB<5>
  VSS40  = GND
  \dqs9_b_t||tdqs9_b_t||dbi4_b_n\  = M_D_CPU0_SB_DQS_DP<9>
  \dqs9_b_c||tdqs9_b_c\  = M_D_CPU0_SB_DQS_DN<9>
  VSS41  = GND
  CB0_B  = M_D_CPU0_SB_CB<0>
  VSS42  = GND
  CB1_B  = M_D_CPU0_SB_CB<1>
  VSS43  = GND
  DQ0_B  = M_D_CPU0_SB_DQ<0>
  VSS44  = GND
  DQ1_B  = M_D_CPU0_SB_DQ<1>
  VSS45  = GND
  DQS0_B_T  = M_D_CPU0_SB_DQS_DP<0>
  DQS0_B_C  = M_D_CPU0_SB_DQS_DN<0>
  VSS46  = GND
  DQ4_B  = M_D_CPU0_SB_DQ<4>
  VSS47  = GND
  DQ5_B  = M_D_CPU0_SB_DQ<5>
  VSS48  = GND
  DQ8_B  = M_D_CPU0_SB_DQ<8>
  VSS49  = GND
  DQ9_B  = M_D_CPU0_SB_DQ<9>
  VSS50  = GND
  DQS1_B_T  = M_D_CPU0_SB_DQS_DP<1>
  DQS1_B_C  = M_D_CPU0_SB_DQS_DN<1>
  VSS51  = GND
  DQ12_B  = M_D_CPU0_SB_DQ<12>
  VSS52  = GND
  DQ13_B  = M_D_CPU0_SB_DQ<13>
  VSS53  = GND
  DQ16_B  = M_D_CPU0_SB_DQ<16>
  VSS54  = GND
  DQ17_B  = M_D_CPU0_SB_DQ<17>
  VSS55  = GND
  DQS2_B_T  = M_D_CPU0_SB_DQS_DP<2>
  DQS2_B_C  = M_D_CPU0_SB_DQS_DN<2>
  VSS56  = GND
  DQ20_B  = M_D_CPU0_SB_DQ<20>
  VSS57  = GND
  DQ21_B  = M_D_CPU0_SB_DQ<21>
  VSS58  = GND
  DQ24_B  = M_D_CPU0_SB_DQ<24>
  VSS59  = GND
  DQ25_B  = M_D_CPU0_SB_DQ<25>
  VSS60  = GND
  DQS3_B_T  = M_D_CPU0_SB_DQS_DP<3>
  DQS3_B_C  = M_D_CPU0_SB_DQS_DN<3>
  VSS61  = GND
  DQ28_B  = M_D_CPU0_SB_DQ<28>
  VSS62  = GND
  DQ29_B  = M_D_CPU0_SB_DQ<29>
  VSS63  = GND
  RFU1  = NC
  VIN_BULK1  = P12V_MEM_CPU0
  VIN_BULK2  = P12V_MEM_CPU0
  \pwr_good||fail_n\  = PWRGD_CHD_CPU0_DIMM
  HAS  = PD_CHD_CPU0_DIMM_SAA
  RFU2  = NC
  RFU3  = NC
  VSS64  = GND
  DQ2_A  = M_D_CPU0_SA_DQ<2>
  VSS65  = GND
  DQ3_A  = M_D_CPU0_SA_DQ<3>
  VSS66  = GND
  \dqs5_a_c||tdqs5_a_c||dqs5_a_t||tdqs5_a_t\  = M_D_CPU0_SA_DQS_DN<5>
  \dqs5_a_t||tdqs5_a_t\  = M_D_CPU0_SA_DQS_DP<5>
  VSS67  = GND
  DQ6_A  = M_D_CPU0_SA_DQ<6>
  VSS68  = GND
  DQ7_A  = M_D_CPU0_SA_DQ<7>
  VSS69  = GND
  DQ10_A  = M_D_CPU0_SA_DQ<10>
  VSS70  = GND
  DQ11_A  = M_D_CPU0_SA_DQ<11>
  VSS71  = GND
  \dqs6_a_c||tdqs6_a_c||dqs6_a_t||tdqs6_a_t\  = M_D_CPU0_SA_DQS_DN<6>
  \dqs6_a_t||tdqs6_a_t\  = M_D_CPU0_SA_DQS_DP<6>
  VSS72  = GND
  DQ14_A  = M_D_CPU0_SA_DQ<14>
  VSS73  = GND
  DQ15_A  = M_D_CPU0_SA_DQ<15>
  VSS74  = GND
  DQ18_A  = M_D_CPU0_SA_DQ<18>
  VSS75  = GND
  DQ19_A  = M_D_CPU0_SA_DQ<19>
  VSS76  = GND
  \dqs7_a_c||tdqs7_a_c\  = M_D_CPU0_SA_DQS_DN<7>
  \dqs7_a_t||tdqs7_a_t\  = M_D_CPU0_SA_DQS_DP<7>
  VSS77  = GND
  DQ22_A  = M_D_CPU0_SA_DQ<22>
  VSS78  = GND
  DQ23_A  = M_D_CPU0_SA_DQ<23>
  VSS79  = GND
  DQ26_A  = M_D_CPU0_SA_DQ<26>
  VSS80  = GND
  DQ27_A  = M_D_CPU0_SA_DQ<27>
  VSS81  = GND
  \dqs8_a_c||tdqs8_a_c\  = M_D_CPU0_SA_DQS_DN<8>
  \dqs8_a_t||tdqs8_a_t\  = M_D_CPU0_SA_DQS_DP<8>
  VSS82  = GND
  DQ30_A  = M_D_CPU0_SA_DQ<30>
  VSS83  = GND
  DQ31_A  = M_D_CPU0_SA_DQ<31>
  VSS84  = GND
  CB2_A  = M_D_CPU0_SA_CB<2>
  VSS85  = GND
  CB3_A  = M_D_CPU0_SA_CB<3>
  VSS86  = GND
  \dqs9_a_c||tdqs9_a_c\  = M_D_CPU0_SA_DQS_DN<9>
  \dqs9_a_t||tdqs9_a_t\  = M_D_CPU0_SA_DQS_DP<9>
  VSS87  = GND
  CB6_A  = M_D_CPU0_SA_CB<6>
  VSS88  = GND
  CB7_A  = M_D_CPU0_SA_CB<7>
  VSS89  = GND
  RESET_N  = M_D_CPU0_RESET_N
  VSS90  = GND
  CS1_A_N  = M_D_CPU0_SA_CS_N<1>
  VSS91  = GND
  CA1_A  = M_D_CPU0_SA_CA<1>
  VSS92  = GND
  CA3_A  = M_D_CPU0_SA_CA<3>
  VSS93  = GND
  CA5_A  = M_D_CPU0_SA_CA<5>
  VSS94  = GND
  CK_T  = M_D_CPU0_CLK_DP<0>
  CK_C  = M_D_CPU0_CLK_DN<0>
  VSS95  = GND
  RFU4  = NC
  CA1_B  = M_D_CPU0_SB_CA<1>
  VSS96  = GND
  CA3_B  = M_D_CPU0_SB_CA<3>
  VSS97  = GND
  CA5_B  = M_D_CPU0_SB_CA<5>
  VSS98  = GND
  PAR_B  = M_D_CPU0_SB_PAR
  VSS99  = GND
  CS1_B_N  = M_D_CPU0_SB_CS_N<1>
  VSS100  = GND
  RFU5  = NC
  RFU6  = NC
  VSS101  = GND
  CB6_B  = M_D_CPU0_SB_CB<6>
  VSS102  = GND
  CB7_B  = M_D_CPU0_SB_CB<7>
  VSS103  = GND
  DQS4_B_C  = M_D_CPU0_SB_DQS_DN<4>
  DQS4_B_T  = M_D_CPU0_SB_DQS_DP<4>
  VSS104  = GND
  CB2_B  = M_D_CPU0_SB_CB<2>
  VSS105  = GND
  CB3_B  = M_D_CPU0_SB_CB<3>
  VSS106  = GND
  DQ2_B  = M_D_CPU0_SB_DQ<2>
  VSS107  = GND
  DQ3_B  = M_D_CPU0_SB_DQ<3>
  VSS108  = GND
  \dqs5_b_c||tdqs5_b_c\  = M_D_CPU0_SB_DQS_DN<5>
  \dqs5_b_t||tdqs5_b_t\  = M_D_CPU0_SB_DQS_DP<5>
  VSS109  = GND
  DQ6_B  = M_D_CPU0_SB_DQ<6>
  VSS110  = GND
  DQ7_B  = M_D_CPU0_SB_DQ<7>
  VSS111  = GND
  DQ10_B  = M_D_CPU0_SB_DQ<10>
  VSS112  = GND
  DQ11_B  = M_D_CPU0_SB_DQ<11>
  VSS113  = GND
  \dqs6_b_c||tdqs6_b_c\  = M_D_CPU0_SB_DQS_DN<6>
  \dqs6_b_t||tdqs6_b_t\  = M_D_CPU0_SB_DQS_DP<6>
  VSS114  = GND
  DQ14_B  = M_D_CPU0_SB_DQ<14>
  VSS115  = GND
  DQ15_B  = M_D_CPU0_SB_DQ<15>
  VSS116  = GND
  DQ18_B  = M_D_CPU0_SB_DQ<18>
  VSS117  = GND
  DQ19_B  = M_D_CPU0_SB_DQ<19>
  VSS118  = GND
  \dqs7_b_c||tdqs7_b_c\  = M_D_CPU0_SB_DQS_DN<7>
  \dqs7_b_t||tdqs7_b_t\  = M_D_CPU0_SB_DQS_DP<7>
  VSS119  = GND
  DQ22_B  = M_D_CPU0_SB_DQ<22>
  VSS120  = GND
  DQ23_B  = M_D_CPU0_SB_DQ<23>
  VSS121  = GND
  DQ26_B  = M_D_CPU0_SB_DQ<26>
  VSS122  = GND
  DQ27_B  = M_D_CPU0_SB_DQ<27>
  VSS123  = GND
  \dqs8_b_c||tdqs8_b_c\  = M_D_CPU0_SB_DQS_DN<8>
  \dqs8_b_t||tdqs8_b_t\  = M_D_CPU0_SB_DQS_DP<8>
  VSS124  = GND
  DQ30_B  = M_D_CPU0_SB_DQ<30>
  VSS125  = GND
  DQ31_B  = M_D_CPU0_SB_DQ<31>
  VSS126  = GND
  G1  = GND
  G2  = GND
  G3  = GND

(kicad_pcb
	(version 20260206)
	(generator "pcbnew")
	(generator_version "10.0")
	(general
		(thickness 1.6)
		(legacy_teardrops no)
	)
	(paper "A4")
	(title_block
		(title "04192023_DAF0TMB3IC0_F0TG_MB_C_brd_V02_OCP.brd")
		(comment 1 "Grand Teton / footprint 2350 of 8354 (J19), pads 93-138 of 291")
	)
	(layers
		(0 "F.Cu" signal "TOP")
		(4 "In1.Cu" signal "GND")
		(6 "In2.Cu" signal "IN1")
		(8 "In3.Cu" signal "GND1")
		(10 "In4.Cu" signal "IN2")
		(12 "In5.Cu" signal "GND2")
		(14 "In6.Cu" signal "IN3")
		(16 "In7.Cu" signal "GND3")
		(18 "In8.Cu" signal "VCC")
		(20 "In9.Cu" signal "VCC1")
		(22 "In10.Cu" signal "GND4")
		(24 "In11.Cu" signal "IN4")
		(26 "In12.Cu" signal "GND5")
		(28 "In13.Cu" signal "IN5")
		(30 "In14.Cu" signal "GND6")
		(32 "In15.Cu" signal "IN6")
		(34 "In16.Cu" signal "GND7")
		(2 "B.Cu" signal "BOTTOM")
		(9 "F.Adhes" user "F.Adhesive")
		(11 "B.Adhes" user "B.Adhesive")
		(13 "F.Paste" user "Package Geometry/Pastemask Top")
		(15 "B.Paste" user "Package Geometry/Pastemask Bottom")
		(5 "F.SilkS" user "Ref Des/Silkscreen Top")
		(7 "B.SilkS" user "Ref Des/Silkscreen Bottom")
		(1 "F.Mask" user "Board Geometry/Soldermask Top")
		(3 "B.Mask" user "Board Geometry/Soldermask Bottom")
		(17 "Dwgs.User" user "User.Drawings")
		(19 "Cmts.User" user "User.Comments")
		(21 "Eco1.User" user "User.Eco1")
		(23 "Eco2.User" user "User.Eco2")
		(25 "Edge.Cuts" user "Board Geometry/Outline")
		(27 "Margin" user)
		(31 "F.CrtYd" user "Package Geometry/Place Bound Top")
		(29 "B.CrtYd" user "Package Geometry/Place Bound Bottom")
		(35 "F.Fab" user "Ref Des/Assembly Top")
		(33 "B.Fab" user "Ref Des/Assembly Bottom")
	)
	(footprint ""
		(layer "F.Cu")
		(at 282.685998 -255.560068 180)
		(property "Reference" "J19"
			(at -2.2098 -81.984088 0)
			(unlocked yes)
			(layer "F.SilkS")
			(effects
				(font
					(size 0.7874 0.5842)
					(thickness 0.1524)
				)
			)
		)
		(property "Value" ""
			(at 0 0 180)
			(layer "F.Fab")
			(effects
				(font
					(size 1.27 1.27)
				)
			)
		)
		(duplicate_pad_numbers_are_jumpers no)
		(pad "93" smd rect
			(at -2.050034 19.975068 90)
			(size 0.519938 1.4986)
			(layers "F.Cu" "F.Mask" "F.Paste")
			(net "M_D_CPU0_SB_DQS_DP<9>")
		)
		(pad "94" smd rect
			(at -2.050034 20.824952 90)
			(size 0.519938 1.4986)
			(layers "F.Cu" "F.Mask" "F.Paste")
			(net "M_D_CPU0_SB_DQS_DN<9>")
		)
		(pad "95" smd rect
			(at -2.050034 21.67509 90)
			(size 0.519938 1.4986)
			(layers "F.Cu" "F.Mask" "F.Paste")
			(net "GND")
		)
		(pad "96" smd rect
			(at -2.050034 22.524974 90)
			(size 0.519938 1.4986)
			(layers "F.Cu" "F.Mask" "F.Paste")
			(net "M_D_CPU0_SB_CB<0>")
		)
		(pad "97" smd rect
			(at -2.050034 23.375112 90)
			(size 0.519938 1.4986)
			(layers "F.Cu" "F.Mask" "F.Paste")
			(net "GND")
		)
		(pad "98" smd rect
			(at -2.050034 24.224996 90)
			(size 0.519938 1.4986)
			(layers "F.Cu" "F.Mask" "F.Paste")
			(net "M_D_CPU0_SB_CB<1>")
		)
		(pad "99" smd rect
			(at -2.050034 25.07488 90)
			(size 0.519938 1.4986)
			(layers "F.Cu" "F.Mask" "F.Paste")
			(net "GND")
		)
		(pad "100" smd rect
			(at -2.050034 25.925018 90)
			(size 0.519938 1.4986)
			(layers "F.Cu" "F.Mask" "F.Paste")
			(net "M_D_CPU0_SB_DQ<0>")
		)
		(pad "101" smd rect
			(at -2.050034 26.774902 90)
			(size 0.519938 1.4986)
			(layers "F.Cu" "F.Mask" "F.Paste")
			(net "GND")
		)
		(pad "102" smd rect
			(at -2.050034 27.62504 90)
			(size 0.519938 1.4986)
			(layers "F.Cu" "F.Mask" "F.Paste")
			(net "M_D_CPU0_SB_DQ<1>")
		)
		(pad "103" smd rect
			(at -2.050034 28.474924 90)
			(size 0.519938 1.4986)
			(layers "F.Cu" "F.Mask" "F.Paste")
			(net "GND")
		)
		(pad "104" smd rect
			(at -2.050034 29.325062 90)
			(size 0.519938 1.4986)
			(layers "F.Cu" "F.Mask" "F.Paste")
			(net "M_D_CPU0_SB_DQS_DP<0>")
		)
		(pad "105" smd rect
			(at -2.050034 30.174946 90)
			(size 0.519938 1.4986)
			(layers "F.Cu" "F.Mask" "F.Paste")
			(net "M_D_CPU0_SB_DQS_DN<0>")
		)
		(pad "106" smd rect
			(at -2.050034 31.025084 90)
			(size 0.519938 1.4986)
			(layers "F.Cu" "F.Mask" "F.Paste")
			(net "GND")
		)
		(pad "107" smd rect
			(at -2.050034 31.874968 90)
			(size 0.519938 1.4986)
			(layers "F.Cu" "F.Mask" "F.Paste")
			(net "M_D_CPU0_SB_DQ<4>")
		)
		(pad "108" smd rect
			(at -2.050034 32.725106 90)
			(size 0.519938 1.4986)
			(layers "F.Cu" "F.Mask" "F.Paste")
			(net "GND")
		)
		(pad "109" smd rect
			(at -2.050034 33.57499 90)
			(size 0.519938 1.4986)
			(layers "F.Cu" "F.Mask" "F.Paste")
			(net "M_D_CPU0_SB_DQ<5>")
		)
		(pad "110" smd rect
			(at -2.050034 34.425128 90)
			(size 0.519938 1.4986)
			(layers "F.Cu" "F.Mask" "F.Paste")
			(net "GND")
		)
		(pad "111" smd rect
			(at -2.050034 35.275012 90)
			(size 0.519938 1.4986)
			(layers "F.Cu" "F.Mask" "F.Paste")
			(net "M_D_CPU0_SB_DQ<8>")
		)
		(pad "112" smd rect
			(at -2.050034 36.124896 90)
			(size 0.519938 1.4986)
			(layers "F.Cu" "F.Mask" "F.Paste")
			(net "GND")
		)
		(pad "113" smd rect
			(at -2.050034 36.975034 90)
			(size 0.519938 1.4986)
			(layers "F.Cu" "F.Mask" "F.Paste")
			(net "M_D_CPU0_SB_DQ<9>")
		)
		(pad "114" smd rect
			(at -2.050034 37.824918 90)
			(size 0.519938 1.4986)
			(layers "F.Cu" "F.Mask" "F.Paste")
			(net "GND")
		)
		(pad "115" smd rect
			(at -2.050034 38.675056 90)
			(size 0.519938 1.4986)
			(layers "F.Cu" "F.Mask" "F.Paste")
			(net "M_D_CPU0_SB_DQS_DP<1>")
		)
		(pad "116" smd rect
			(at -2.050034 39.52494 90)
			(size 0.519938 1.4986)
			(layers "F.Cu" "F.Mask" "F.Paste")
			(net "M_D_CPU0_SB_DQS_DN<1>")
		)
		(pad "117" smd rect
			(at -2.050034 40.375078 90)
			(size 0.519938 1.4986)
			(layers "F.Cu" "F.Mask" "F.Paste")
			(net "GND")
		)
		(pad "118" smd rect
			(at -2.050034 41.224962 90)
			(size 0.519938 1.4986)
			(layers "F.Cu" "F.Mask" "F.Paste")
			(net "M_D_CPU0_SB_DQ<12>")
		)
		(pad "119" smd rect
			(at -2.050034 42.0751 90)
			(size 0.519938 1.4986)
			(layers "F.Cu" "F.Mask" "F.Paste")
			(net "GND")
		)
		(pad "120" smd rect
			(at -2.050034 42.924984 90)
			(size 0.519938 1.4986)
			(layers "F.Cu" "F.Mask" "F.Paste")
			(net "M_D_CPU0_SB_DQ<13>")
		)
		(pad "121" smd rect
			(at -2.050034 43.775122 90)
			(size 0.519938 1.4986)
			(layers "F.Cu" "F.Mask" "F.Paste")
			(net "GND")
		)
		(pad "122" smd rect
			(at -2.050034 44.625006 90)
			(size 0.519938 1.4986)
			(layers "F.Cu" "F.Mask" "F.Paste")
			(net "M_D_CPU0_SB_DQ<16>")
		)
		(pad "123" smd rect
			(at -2.050034 45.47489 90)
			(size 0.519938 1.4986)
			(layers "F.Cu" "F.Mask" "F.Paste")
			(net "GND")
		)
		(pad "124" smd rect
			(at -2.050034 46.325028 90)
			(size 0.519938 1.4986)
			(layers "F.Cu" "F.Mask" "F.Paste")
			(net "M_D_CPU0_SB_DQ<17>")
		)
		(pad "125" smd rect
			(at -2.050034 47.174912 90)
			(size 0.519938 1.4986)
			(layers "F.Cu" "F.Mask" "F.Paste")
			(net "GND")
		)
		(pad "126" smd rect
			(at -2.050034 48.02505 90)
			(size 0.519938 1.4986)
			(layers "F.Cu" "F.Mask" "F.Paste")
			(net "M_D_CPU0_SB_DQS_DP<2>")
		)
		(pad "127" smd rect
			(at -2.050034 48.874934 90)
			(size 0.519938 1.4986)
			(layers "F.Cu" "F.Mask" "F.Paste")
			(net "M_D_CPU0_SB_DQS_DN<2>")
		)
		(pad "128" smd rect
			(at -2.050034 49.725072 90)
			(size 0.519938 1.4986)
			(layers "F.Cu" "F.Mask" "F.Paste")
			(net "GND")
		)
		(pad "129" smd rect
			(at -2.050034 50.574956 90)
			(size 0.519938 1.4986)
			(layers "F.Cu" "F.Mask" "F.Paste")
			(net "M_D_CPU0_SB_DQ<20>")
		)
		(pad "130" smd rect
			(at -2.050034 51.425094 90)
			(size 0.519938 1.4986)
			(layers "F.Cu" "F.Mask" "F.Paste")
			(net "GND")
		)
		(pad "131" smd rect
			(at -2.050034 52.274978 90)
			(size 0.519938 1.4986)
			(layers "F.Cu" "F.Mask" "F.Paste")
			(net "M_D_CPU0_SB_DQ<21>")
		)
		(pad "132" smd rect
			(at -2.050034 53.125116 90)
			(size 0.519938 1.4986)
			(layers "F.Cu" "F.Mask" "F.Paste")
			(net "GND")
		)
		(pad "133" smd rect
			(at -2.050034 53.975 90)
			(size 0.519938 1.4986)
			(layers "F.Cu" "F.Mask" "F.Paste")
			(net "M_D_CPU0_SB_DQ<24>")
		)
		(pad "134" smd rect
			(at -2.050034 54.824884 90)
			(size 0.519938 1.4986)
			(layers "F.Cu" "F.Mask" "F.Paste")
			(net "GND")
		)
		(pad "135" smd rect
			(at -2.050034 55.675022 90)
			(size 0.519938 1.4986)
			(layers "F.Cu" "F.Mask" "F.Paste")
			(net "M_D_CPU0_SB_DQ<25>")
		)
		(pad "136" smd rect
			(at -2.050034 56.524906 90)
			(size 0.519938 1.4986)
			(layers "F.Cu" "F.Mask" "F.Paste")
			(net "GND")
		)
		(pad "137" smd rect
			(at -2.050034 57.375044 90)
			(size 0.519938 1.4986)
			(layers "F.Cu" "F.Mask" "F.Paste")
			(net "M_D_CPU0_SB_DQS_DP<3>")
		)
		(pad "138" smd rect
			(at -2.050034 58.224928 90)
			(size 0.519938 1.4986)
			(layers "F.Cu" "F.Mask" "F.Paste")
			(net "M_D_CPU0_SB_DQS_DN<3>")
		)
	)
)
